G04 ================== begin FILE IDENTIFICATION RECORD ==================*
G04 Layout Name:  14545-sa.brd*
G04 Film Name:    BMASK*
G04 File Format:  Gerber RS274X*
G04 File Origin:  Cadence Allegro 16.5-S056*
G04 Origin Date:  Fri Aug 01 17:58:07 2014*
G04 *
G04 Layer:  VIA CLASS/SOLDERMASK_BOTTOM*
G04 Layer:  PIN/SOLDERMASK_BOTTOM*
G04 Layer:  PACKAGE GEOMETRY/SOLDERMASK_BOTTOM*
G04 Layer:  DRAWING FORMAT/LAYER_PCB_STORY*
G04 Layer:  DRAWING FORMAT/LAYER_SOLDER_B*
G04 Layer:  BOARD GEOMETRY/SOLDERMASK_BOTTOM*
G04 *
G04 Offset:    (0.00 0.00)*
G04 Mirror:    No*
G04 Mode:      Positive*
G04 Rotation:  0*
G04 FullContactRelief:  No*
G04 UndefLineWidth:     6.00*
G04 ================== end FILE IDENTIFICATION RECORD ====================*
%FSLAX35Y35*MOIN*%
%IR0*IPPOS*OFA0.00000B0.00000*MIA0B0*SFA1.00000B1.00000*%
%ADD16O,.103X.06*%
%ADD18R,.23X.032*%
%ADD13R,.142X.028*%
%ADD17C,.073*%
%ADD15C,.028*%
%ADD12C,.091*%
%ADD11C,.086*%
%ADD14C,.315*%
%ADD19C,.146*%
%ADD10R,.16X.16*%
%ADD20C,.02*%
%ADD21C,.006*%
G75*
%LPD*%
G75*
G36*
G01X1017308Y1473722D02*
Y1491397D01*
X991708D01*
Y1473722D01*
X1017308D01*
G37*
G36*
G01Y1453247D02*
Y1470922D01*
X991708D01*
Y1453247D01*
X1017308D01*
G37*
G36*
G01Y1433722D02*
Y1451397D01*
X991708D01*
Y1433722D01*
X1017308D01*
G37*
G36*
G01Y1553722D02*
Y1571397D01*
X991708D01*
Y1553722D01*
X1017308D01*
G37*
G36*
G01Y1533247D02*
Y1550922D01*
X991708D01*
Y1533247D01*
X1017308D01*
G37*
G36*
G01Y1513722D02*
Y1531397D01*
X991708D01*
Y1513722D01*
X1017308D01*
G37*
G36*
G01Y1493247D02*
Y1510922D01*
X991708D01*
Y1493247D01*
X1017308D01*
G37*
G36*
G01X1017307Y1593722D02*
Y1610922D01*
X991708D01*
Y1593722D01*
X1017307D01*
G37*
G36*
G01X1017308Y1573247D02*
Y1590922D01*
X991708D01*
Y1573247D01*
X1017308D01*
G37*
G54D10*
X-30766Y56622D03*
X-33866Y1947322D03*
X21499Y17050D03*
X1010999Y18550D03*
X1008999Y1968550D03*
X1073334Y50022D03*
G54D20*
G01X-71137Y-139897D02*
Y-219897D01*
G01D02*
X1129963D01*
G01X-75137Y-123897D02*
G02I-12000J0D01*
G01X-80287D02*
G02I-6850J0D01*
G01X-87137Y-139897D02*
Y-107897D01*
G01X-71137Y-123897D02*
X-103137D01*
G01X-71137Y-139897D02*
X1129963D01*
G01X-71137Y-175397D02*
X1129963D01*
G01X342463Y-139897D02*
Y-219897D01*
G01X479963Y-139897D02*
Y-219897D01*
G01X594963Y-139897D02*
Y-219897D01*
G01X762463Y-139897D02*
Y-219897D01*
G01X932463Y-139897D02*
Y-219897D01*
G01X1129963Y-139897D02*
Y-219897D01*
G01X1157963Y-123897D02*
G02I-12000J0D01*
G01X1152813D02*
G02I-6850J0D01*
G01X1145963Y-139897D02*
Y-107897D01*
G01X1161963Y-123897D02*
X1129963D01*
G54D11*
X-39052Y28742D03*
X-43327Y310478D03*
X-39686Y917251D03*
X-38801Y1082342D03*
X-44886Y1294251D03*
X-43103Y1928864D03*
X1071932Y32074D03*
X1074813Y1348051D03*
X1076613Y1740651D03*
X1074813Y1957551D03*
G54D21*
G01X-89222Y-207897D02*
Y-190397D01*
G01X-80052D02*
Y-207897D01*
G01Y-199147D02*
X-89222D01*
G01X-67137Y-207897D02*
X-68447Y-207605D01*
X-69757Y-206439D01*
X-70631Y-204397D01*
X-71067Y-202064D01*
X-70631Y-199730D01*
X-69757Y-197689D01*
X-68447Y-196522D01*
X-67137Y-196231D01*
X-65827Y-196522D01*
X-64517Y-197689D01*
X-63644Y-199730D01*
X-63425Y-202064D01*
X-63644Y-204397D01*
X-64517Y-206439D01*
X-65827Y-207605D01*
X-67137Y-207897D01*
G01X-53349D02*
Y-196231D01*
G01Y-199147D02*
X-52475Y-197689D01*
X-51165Y-196522D01*
X-49419Y-196231D01*
X-47891Y-196522D01*
X-46580Y-197689D01*
X-45925Y-199730D01*
Y-207897D01*
G01X-35412Y-200022D02*
X-28425D01*
X-29080Y-197980D01*
X-30172Y-196814D01*
X-31700Y-196231D01*
X-33229Y-196522D01*
X-34539Y-197397D01*
X-35412Y-199439D01*
X-35849Y-201189D01*
Y-202939D01*
X-35412Y-204689D01*
X-34320Y-206439D01*
X-33010Y-207605D01*
X-31482Y-207897D01*
X-29954Y-207314D01*
X-28425Y-205564D01*
G01X-19222Y-213147D02*
X-17912Y-213730D01*
X-16165Y-213147D01*
X-15074Y-211981D01*
X-14200Y-210522D01*
X-12891Y-205856D01*
X-10052Y-196231D01*
G01X-17039D02*
X-12891Y-205856D01*
G01X22109Y-198564D02*
X22983Y-197689D01*
X23638Y-196231D01*
X24075Y-194188D01*
X23638Y-192439D01*
X22765Y-191272D01*
X21236Y-190397D01*
X15341D01*
Y-207897D01*
X22546D01*
X24075Y-206731D01*
X24948Y-204980D01*
X25385Y-202939D01*
X24948Y-200897D01*
X23638Y-199147D01*
X22109Y-198564D01*
X15341D01*
G01X41793Y-207897D02*
Y-196231D01*
G01Y-198272D02*
X40920Y-197106D01*
X39609Y-196522D01*
X38081Y-196231D01*
X36553Y-196814D01*
X35243Y-197980D01*
X34369Y-199730D01*
X33933Y-202064D01*
X34369Y-204397D01*
X35243Y-206147D01*
X36553Y-207314D01*
X38081Y-207897D01*
X39609Y-207605D01*
X40920Y-206731D01*
X41793Y-205564D01*
G01X59293Y-190397D02*
Y-207897D01*
G01Y-205273D02*
X58420Y-206731D01*
X57109Y-207605D01*
X55581Y-207897D01*
X53835Y-207314D01*
X52525Y-205856D01*
X51651Y-204106D01*
X51433Y-202064D01*
X51651Y-200022D01*
X52525Y-198272D01*
X53835Y-196814D01*
X55581Y-196231D01*
X57109Y-196522D01*
X58201Y-197106D01*
X59293Y-198272D01*
G01X69806Y-212272D02*
X71335Y-213439D01*
X73081Y-213730D01*
X74609Y-213439D01*
X75920Y-211981D01*
X76793Y-209939D01*
Y-196231D01*
G01Y-198564D02*
X75920Y-197397D01*
X74609Y-196522D01*
X73081Y-196231D01*
X71335Y-196814D01*
X70243Y-197980D01*
X69369Y-200022D01*
X68933Y-202064D01*
X69151Y-203814D01*
X70025Y-205856D01*
X71335Y-207314D01*
X73081Y-207897D01*
X74391Y-207605D01*
X75920Y-206439D01*
X76793Y-205273D01*
G01X87088Y-200022D02*
X94075D01*
X93420Y-197980D01*
X92328Y-196814D01*
X90800Y-196231D01*
X89271Y-196522D01*
X87961Y-197397D01*
X87088Y-199439D01*
X86651Y-201189D01*
Y-202939D01*
X87088Y-204689D01*
X88180Y-206439D01*
X89490Y-207605D01*
X91018Y-207897D01*
X92546Y-207314D01*
X94075Y-205564D01*
G01X104806Y-207897D02*
Y-196231D01*
G01Y-198564D02*
X105898Y-197397D01*
X106990Y-196522D01*
X108518Y-196231D01*
X109609Y-196522D01*
X110920Y-197397D01*
G01X138060Y-207897D02*
Y-190397D01*
X142426D01*
X144173Y-191272D01*
X145483Y-192439D01*
X146575Y-194188D01*
X147448Y-196231D01*
X147666Y-199147D01*
X147448Y-202064D01*
X146575Y-204106D01*
X145483Y-205856D01*
X144173Y-207022D01*
X142426Y-207897D01*
X138060D01*
G01X155996D02*
Y-190397D01*
X161236D01*
X162983Y-191272D01*
X164293Y-193314D01*
X164730Y-195647D01*
X164293Y-197980D01*
X163201Y-199730D01*
X161236Y-200606D01*
X155996D01*
G01X179609Y-198564D02*
X180483Y-197689D01*
X181138Y-196231D01*
X181575Y-194188D01*
X181138Y-192439D01*
X180265Y-191272D01*
X178736Y-190397D01*
X172841D01*
Y-207897D01*
X180046D01*
X181575Y-206731D01*
X182448Y-204980D01*
X182885Y-202939D01*
X182448Y-200897D01*
X181138Y-199147D01*
X179609Y-198564D01*
X172841D01*
G01X208496Y-190397D02*
Y-207897D01*
X217230D01*
G01X230363D02*
X229053Y-207605D01*
X227743Y-206439D01*
X226869Y-204397D01*
X226433Y-202064D01*
X226869Y-199730D01*
X227743Y-197689D01*
X229053Y-196522D01*
X230363Y-196231D01*
X231673Y-196522D01*
X232983Y-197689D01*
X233856Y-199730D01*
X234075Y-202064D01*
X233856Y-204397D01*
X232983Y-206439D01*
X231673Y-207605D01*
X230363Y-207897D01*
G01X242404Y-196231D02*
X245025Y-207897D01*
X247863Y-196231D01*
X250701Y-207897D01*
X253322Y-196231D01*
G01X278496Y-190397D02*
Y-207897D01*
X287230D01*
G01X300363D02*
X299053Y-207605D01*
X297743Y-206439D01*
X296869Y-204397D01*
X296433Y-202064D01*
X296869Y-199730D01*
X297743Y-197689D01*
X299053Y-196522D01*
X300363Y-196231D01*
X301673Y-196522D01*
X302983Y-197689D01*
X303856Y-199730D01*
X304075Y-202064D01*
X303856Y-204397D01*
X302983Y-206439D01*
X301673Y-207605D01*
X300363Y-207897D01*
G01X314588Y-205856D02*
X315680Y-207022D01*
X317208Y-207897D01*
X318518D01*
X319828Y-207314D01*
X320701Y-206439D01*
X321138Y-205273D01*
X320920Y-203522D01*
X320046Y-202647D01*
X316116Y-200897D01*
X315243Y-198855D01*
X315680Y-197397D01*
X316553Y-196522D01*
X317863Y-196231D01*
X319173Y-196522D01*
X320483Y-197397D01*
G01X332088Y-205856D02*
X333180Y-207022D01*
X334708Y-207897D01*
X336018D01*
X337328Y-207314D01*
X338201Y-206439D01*
X338638Y-205273D01*
X338420Y-203522D01*
X337546Y-202647D01*
X333616Y-200897D01*
X332743Y-198855D01*
X333180Y-197397D01*
X334053Y-196522D01*
X335363Y-196231D01*
X336673Y-196522D01*
X337983Y-197397D01*
G01X94686Y-164897D02*
Y-147397D01*
X100363Y-161980D01*
X106040Y-147397D01*
Y-164897D01*
G01X117863D02*
X116553Y-164605D01*
X115243Y-163439D01*
X114369Y-161397D01*
X113933Y-159064D01*
X114369Y-156730D01*
X115243Y-154689D01*
X116553Y-153522D01*
X117863Y-153231D01*
X119173Y-153522D01*
X120483Y-154689D01*
X121356Y-156730D01*
X121575Y-159064D01*
X121356Y-161397D01*
X120483Y-163439D01*
X119173Y-164605D01*
X117863Y-164897D01*
G01X139293Y-147397D02*
Y-164897D01*
G01Y-162273D02*
X138420Y-163731D01*
X137109Y-164605D01*
X135581Y-164897D01*
X133835Y-164314D01*
X132525Y-162856D01*
X131651Y-161106D01*
X131433Y-159064D01*
X131651Y-157022D01*
X132525Y-155272D01*
X133835Y-153814D01*
X135581Y-153231D01*
X137109Y-153522D01*
X138201Y-154106D01*
X139293Y-155272D01*
G01X149588Y-157022D02*
X156575D01*
X155920Y-154980D01*
X154828Y-153814D01*
X153300Y-153231D01*
X151771Y-153522D01*
X150461Y-154397D01*
X149588Y-156439D01*
X149151Y-158189D01*
Y-159939D01*
X149588Y-161689D01*
X150680Y-163439D01*
X151990Y-164605D01*
X153518Y-164897D01*
X155046Y-164314D01*
X156575Y-162564D01*
G01X170363Y-164897D02*
Y-147397D01*
G01X376163Y-209897D02*
Y-192397D01*
X373543Y-195897D01*
G01Y-209897D02*
X378783D01*
G01X396283D02*
Y-192397D01*
X388204Y-204939D01*
X399122D01*
G01X406360Y-207273D02*
X407669Y-208731D01*
X409198Y-209605D01*
X411163Y-209897D01*
X413128Y-209314D01*
X414656Y-208147D01*
X415748Y-206106D01*
X415966Y-203772D01*
X415530Y-201439D01*
X414438Y-199980D01*
X412909Y-198814D01*
X411381Y-198522D01*
X409853Y-198814D01*
X407888Y-199980D01*
X408543Y-192397D01*
X414438D01*
G01X431283Y-209897D02*
Y-192397D01*
X423204Y-204939D01*
X434122D01*
G01X441360Y-207273D02*
X442669Y-208731D01*
X444198Y-209605D01*
X446163Y-209897D01*
X448128Y-209314D01*
X449656Y-208147D01*
X450748Y-206106D01*
X450966Y-203772D01*
X450530Y-201439D01*
X449438Y-199980D01*
X447909Y-198814D01*
X446381Y-198522D01*
X444853Y-198814D01*
X442888Y-199980D01*
X443543Y-192397D01*
X449438D01*
G01X363046Y-164897D02*
Y-147397D01*
X368286D01*
X370033Y-148272D01*
X371343Y-150314D01*
X371780Y-152647D01*
X371343Y-154980D01*
X370251Y-156730D01*
X368286Y-157606D01*
X363046D01*
G01X389716Y-148856D02*
X388406Y-147980D01*
X386878Y-147397D01*
X385131D01*
X383166Y-148272D01*
X381638Y-149730D01*
X380546Y-151481D01*
X379673Y-154397D01*
X379454Y-157022D01*
X379891Y-159647D01*
X380546Y-161397D01*
X381856Y-163147D01*
X383385Y-164314D01*
X384913Y-164897D01*
X386441D01*
X387970Y-164314D01*
X389280Y-163439D01*
X390372Y-162273D01*
G01X404159Y-155564D02*
X405033Y-154689D01*
X405688Y-153231D01*
X406125Y-151188D01*
X405688Y-149439D01*
X404815Y-148272D01*
X403286Y-147397D01*
X397391D01*
Y-164897D01*
X404596D01*
X406125Y-163731D01*
X406998Y-161980D01*
X407435Y-159939D01*
X406998Y-157897D01*
X405688Y-156147D01*
X404159Y-155564D01*
X397391D01*
G01X413363Y-170730D02*
X426463D01*
G01X432391Y-164897D02*
Y-147397D01*
X442435Y-164897D01*
Y-147397D01*
G01X454913Y-164897D02*
X453166Y-164605D01*
X451638Y-163439D01*
X450328Y-161689D01*
X449454Y-159647D01*
X449018Y-157314D01*
Y-154980D01*
X449454Y-152647D01*
X450328Y-150605D01*
X451638Y-148856D01*
X453166Y-147689D01*
X454913Y-147397D01*
X456659Y-147689D01*
X458188Y-148856D01*
X459498Y-150605D01*
X460372Y-152647D01*
X460808Y-154980D01*
Y-157314D01*
X460372Y-159647D01*
X459498Y-161689D01*
X458188Y-163439D01*
X456659Y-164605D01*
X454913Y-164897D01*
G01X505754Y-147397D02*
X511213Y-164897D01*
X516672Y-147397D01*
G01X533080Y-164897D02*
X524346D01*
Y-147397D01*
X533080D01*
G01X529586Y-155855D02*
X524346D01*
G01X541846Y-164897D02*
Y-147397D01*
X547305D01*
X549051Y-148272D01*
X550143Y-149439D01*
X550580Y-151772D01*
X550143Y-154106D01*
X548833Y-155564D01*
X547305Y-156439D01*
X541846D01*
G01X547305D02*
X550580Y-164897D01*
G01X563713Y-165480D02*
X563276Y-165189D01*
Y-164605D01*
X563713Y-164314D01*
X564150Y-164605D01*
Y-165189D01*
X563713Y-165480D01*
G01X524128Y-207564D02*
X525875Y-209022D01*
X527840Y-209897D01*
X529586D01*
X531333Y-209022D01*
X532643Y-207564D01*
X533298Y-205522D01*
X532861Y-203481D01*
X531770Y-201730D01*
X529805Y-200564D01*
X527185Y-199980D01*
X525656Y-198814D01*
X525001Y-196772D01*
X525438Y-194730D01*
X526530Y-193272D01*
X528058Y-192397D01*
X529586D01*
X531115Y-192980D01*
X532425Y-194439D01*
G01X540754Y-209897D02*
X546213Y-192397D01*
X551672Y-209897D01*
G01X549706Y-203772D02*
X542719D01*
G01X711917Y-200564D02*
X711043Y-199689D01*
X710388Y-198231D01*
X709951Y-196188D01*
X710388Y-194439D01*
X711261Y-193272D01*
X712790Y-192397D01*
X718685D01*
Y-209897D01*
X711480D01*
X709951Y-208731D01*
X709078Y-206980D01*
X708641Y-204939D01*
X709078Y-202897D01*
X710388Y-201147D01*
X711917Y-200564D01*
X718685D01*
G01X701840Y-209897D02*
Y-192397D01*
X696163Y-206980D01*
X690486Y-192397D01*
Y-209897D01*
G01X684122D02*
X678663Y-192397D01*
X673204Y-209897D01*
G01X675170Y-203772D02*
X682157D01*
G01X665748Y-207564D02*
X664001Y-209022D01*
X662036Y-209897D01*
X660290D01*
X658543Y-209022D01*
X657233Y-207564D01*
X656578Y-205522D01*
X657015Y-203481D01*
X658106Y-201730D01*
X660071Y-200564D01*
X662691Y-199980D01*
X664220Y-198814D01*
X664875Y-196772D01*
X664438Y-194730D01*
X663346Y-193272D01*
X661818Y-192397D01*
X660290D01*
X658761Y-192980D01*
X657451Y-194439D01*
G01X648466Y-209897D02*
Y-192397D01*
G01X640170D02*
X648466Y-203189D01*
G01X638860Y-209897D02*
X644755Y-198231D01*
G01X630546Y-147397D02*
Y-164897D01*
X639280D01*
G01X656343D02*
Y-153231D01*
G01Y-155272D02*
X655470Y-154106D01*
X654159Y-153522D01*
X652631Y-153231D01*
X651103Y-153814D01*
X649793Y-154980D01*
X648919Y-156730D01*
X648483Y-159064D01*
X648919Y-161397D01*
X649793Y-163147D01*
X651103Y-164314D01*
X652631Y-164897D01*
X654159Y-164605D01*
X655470Y-163731D01*
X656343Y-162564D01*
G01X665328Y-170147D02*
X666638Y-170730D01*
X668385Y-170147D01*
X669476Y-168981D01*
X670350Y-167522D01*
X671659Y-162856D01*
X674498Y-153231D01*
G01X667511D02*
X671659Y-162856D01*
G01X684138Y-157022D02*
X691125D01*
X690470Y-154980D01*
X689378Y-153814D01*
X687850Y-153231D01*
X686321Y-153522D01*
X685011Y-154397D01*
X684138Y-156439D01*
X683701Y-158189D01*
Y-159939D01*
X684138Y-161689D01*
X685230Y-163439D01*
X686540Y-164605D01*
X688068Y-164897D01*
X689596Y-164314D01*
X691125Y-162564D01*
G01X701856Y-164897D02*
Y-153231D01*
G01Y-155564D02*
X702948Y-154397D01*
X704040Y-153522D01*
X705568Y-153231D01*
X706659Y-153522D01*
X707970Y-154397D01*
G01X719138Y-162856D02*
X720230Y-164022D01*
X721758Y-164897D01*
X723068D01*
X724378Y-164314D01*
X725251Y-163439D01*
X725688Y-162273D01*
X725470Y-160522D01*
X724596Y-159647D01*
X720666Y-157897D01*
X719793Y-155855D01*
X720230Y-154397D01*
X721103Y-153522D01*
X722413Y-153231D01*
X723723Y-153522D01*
X725033Y-154397D01*
G01X790596Y-209897D02*
Y-192397D01*
X796055D01*
X797801Y-193272D01*
X798893Y-194439D01*
X799330Y-196772D01*
X798893Y-199106D01*
X797583Y-200564D01*
X796055Y-201439D01*
X790596D01*
G01X796055D02*
X799330Y-209897D01*
G01X809188Y-202022D02*
X816175D01*
X815520Y-199980D01*
X814428Y-198814D01*
X812900Y-198231D01*
X811371Y-198522D01*
X810061Y-199397D01*
X809188Y-201439D01*
X808751Y-203189D01*
Y-204939D01*
X809188Y-206689D01*
X810280Y-208439D01*
X811590Y-209605D01*
X813118Y-209897D01*
X814646Y-209314D01*
X816175Y-207564D01*
G01X826033Y-209897D02*
Y-192397D01*
G01Y-201147D02*
X827125Y-199397D01*
X828435Y-198522D01*
X829745Y-198231D01*
X831709Y-198814D01*
X833020Y-199980D01*
X833893Y-202022D01*
Y-204355D01*
X833456Y-206689D01*
X832583Y-208439D01*
X831055Y-209605D01*
X829745Y-209897D01*
X828435Y-209605D01*
X827125Y-208731D01*
X826033Y-207273D01*
G01X844188Y-202022D02*
X851175D01*
X850520Y-199980D01*
X849428Y-198814D01*
X847900Y-198231D01*
X846371Y-198522D01*
X845061Y-199397D01*
X844188Y-201439D01*
X843751Y-203189D01*
Y-204939D01*
X844188Y-206689D01*
X845280Y-208439D01*
X846590Y-209605D01*
X848118Y-209897D01*
X849646Y-209314D01*
X851175Y-207564D01*
G01X868456Y-199689D02*
X866928Y-198522D01*
X865618Y-198231D01*
X863871Y-198814D01*
X862561Y-199980D01*
X861688Y-202022D01*
X861469Y-204064D01*
X861688Y-206106D01*
X862561Y-207856D01*
X863871Y-209314D01*
X865618Y-209897D01*
X867146Y-209314D01*
X868456Y-208147D01*
G01X885956Y-199689D02*
X884428Y-198522D01*
X883118Y-198231D01*
X881371Y-198814D01*
X880061Y-199980D01*
X879188Y-202022D01*
X878969Y-204064D01*
X879188Y-206106D01*
X880061Y-207856D01*
X881371Y-209314D01*
X883118Y-209897D01*
X884646Y-209314D01*
X885956Y-208147D01*
G01X903893Y-209897D02*
Y-198231D01*
G01Y-200272D02*
X903020Y-199106D01*
X901709Y-198522D01*
X900181Y-198231D01*
X898653Y-198814D01*
X897343Y-199980D01*
X896469Y-201730D01*
X896033Y-204064D01*
X896469Y-206397D01*
X897343Y-208147D01*
X898653Y-209314D01*
X900181Y-209897D01*
X901709Y-209605D01*
X903020Y-208731D01*
X903893Y-207564D01*
G01X781410Y-164897D02*
Y-147397D01*
X785776D01*
X787523Y-148272D01*
X788833Y-149439D01*
X789925Y-151188D01*
X790798Y-153231D01*
X791016Y-156147D01*
X790798Y-159064D01*
X789925Y-161106D01*
X788833Y-162856D01*
X787523Y-164022D01*
X785776Y-164897D01*
X781410D01*
G01X800438Y-157022D02*
X807425D01*
X806770Y-154980D01*
X805678Y-153814D01*
X804150Y-153231D01*
X802621Y-153522D01*
X801311Y-154397D01*
X800438Y-156439D01*
X800001Y-158189D01*
Y-159939D01*
X800438Y-161689D01*
X801530Y-163439D01*
X802840Y-164605D01*
X804368Y-164897D01*
X805896Y-164314D01*
X807425Y-162564D01*
G01X817938Y-162856D02*
X819030Y-164022D01*
X820558Y-164897D01*
X821868D01*
X823178Y-164314D01*
X824051Y-163439D01*
X824488Y-162273D01*
X824270Y-160522D01*
X823396Y-159647D01*
X819466Y-157897D01*
X818593Y-155855D01*
X819030Y-154397D01*
X819903Y-153522D01*
X821213Y-153231D01*
X822523Y-153522D01*
X823833Y-154397D01*
G01X838713Y-153231D02*
Y-164897D01*
G01Y-148564D02*
X838276Y-148272D01*
Y-147689D01*
X838713Y-147397D01*
X839150Y-147689D01*
Y-148272D01*
X838713Y-148564D01*
G01X853156Y-169272D02*
X854685Y-170439D01*
X856431Y-170730D01*
X857959Y-170439D01*
X859270Y-168981D01*
X860143Y-166939D01*
Y-153231D01*
G01Y-155564D02*
X859270Y-154397D01*
X857959Y-153522D01*
X856431Y-153231D01*
X854685Y-153814D01*
X853593Y-154980D01*
X852719Y-157022D01*
X852283Y-159064D01*
X852501Y-160814D01*
X853375Y-162856D01*
X854685Y-164314D01*
X856431Y-164897D01*
X857741Y-164605D01*
X859270Y-163439D01*
X860143Y-162273D01*
G01X870001Y-164897D02*
Y-153231D01*
G01Y-156147D02*
X870875Y-154689D01*
X872185Y-153522D01*
X873931Y-153231D01*
X875459Y-153522D01*
X876770Y-154689D01*
X877425Y-156730D01*
Y-164897D01*
G01X887938Y-157022D02*
X894925D01*
X894270Y-154980D01*
X893178Y-153814D01*
X891650Y-153231D01*
X890121Y-153522D01*
X888811Y-154397D01*
X887938Y-156439D01*
X887501Y-158189D01*
Y-159939D01*
X887938Y-161689D01*
X889030Y-163439D01*
X890340Y-164605D01*
X891868Y-164897D01*
X893396Y-164314D01*
X894925Y-162564D01*
G01X905656Y-164897D02*
Y-153231D01*
G01Y-155564D02*
X906748Y-154397D01*
X907840Y-153522D01*
X909368Y-153231D01*
X910459Y-153522D01*
X911770Y-154397D01*
G01X952413Y-192397D02*
X950666Y-192980D01*
X949356Y-194439D01*
X948483Y-196188D01*
X947828Y-198522D01*
X947610Y-201147D01*
X947828Y-203772D01*
X948483Y-206106D01*
X949356Y-207856D01*
X950666Y-209314D01*
X952413Y-209897D01*
X954159Y-209314D01*
X955470Y-207856D01*
X956343Y-206106D01*
X956998Y-203772D01*
X957216Y-201147D01*
X956998Y-198522D01*
X956343Y-196188D01*
X955470Y-194439D01*
X954159Y-192980D01*
X952413Y-192397D01*
G01X969913Y-209897D02*
X971441Y-209605D01*
X973188Y-208731D01*
X974280Y-207273D01*
X974716Y-205230D01*
X974280Y-203189D01*
X972970Y-201439D01*
X971005Y-200564D01*
X968821D01*
X967511Y-199980D01*
X966419Y-198522D01*
X965983Y-196481D01*
X966638Y-194439D01*
X968166Y-192980D01*
X969913Y-192397D01*
X971659Y-192980D01*
X973188Y-194439D01*
X973843Y-196481D01*
X973406Y-198522D01*
X972315Y-199980D01*
X971005Y-200564D01*
X968821D01*
X966856Y-201439D01*
X965546Y-203189D01*
X965110Y-205230D01*
X965546Y-207273D01*
X966638Y-208731D01*
X968385Y-209605D01*
X969913Y-209897D01*
G01X983483Y-210480D02*
X991343Y-192397D01*
G01X1004913D02*
X1003166Y-192980D01*
X1001856Y-194439D01*
X1000983Y-196188D01*
X1000328Y-198522D01*
X1000110Y-201147D01*
X1000328Y-203772D01*
X1000983Y-206106D01*
X1001856Y-207856D01*
X1003166Y-209314D01*
X1004913Y-209897D01*
X1006659Y-209314D01*
X1007970Y-207856D01*
X1008843Y-206106D01*
X1009498Y-203772D01*
X1009716Y-201147D01*
X1009498Y-198522D01*
X1008843Y-196188D01*
X1007970Y-194439D01*
X1006659Y-192980D01*
X1004913Y-192397D01*
G01X1022413Y-209897D02*
Y-192397D01*
X1019793Y-195897D01*
G01Y-209897D02*
X1025033D01*
G01X1035983Y-210480D02*
X1043843Y-192397D01*
G01X1053265Y-195314D02*
X1054575Y-193564D01*
X1056103Y-192689D01*
X1057850Y-192397D01*
X1060033Y-192980D01*
X1061561Y-194439D01*
X1061998Y-196188D01*
X1061780Y-197939D01*
X1060906Y-199397D01*
X1056540Y-202314D01*
X1054575Y-204355D01*
X1053265Y-207273D01*
X1052828Y-209897D01*
X1061998D01*
G01X1074913Y-192397D02*
X1073166Y-192980D01*
X1071856Y-194439D01*
X1070983Y-196188D01*
X1070328Y-198522D01*
X1070110Y-201147D01*
X1070328Y-203772D01*
X1070983Y-206106D01*
X1071856Y-207856D01*
X1073166Y-209314D01*
X1074913Y-209897D01*
X1076659Y-209314D01*
X1077970Y-207856D01*
X1078843Y-206106D01*
X1079498Y-203772D01*
X1079716Y-201147D01*
X1079498Y-198522D01*
X1078843Y-196188D01*
X1077970Y-194439D01*
X1076659Y-192980D01*
X1074913Y-192397D01*
G01X1092413Y-209897D02*
Y-192397D01*
X1089793Y-195897D01*
G01Y-209897D02*
X1095033D01*
G01X1112533D02*
Y-192397D01*
X1104454Y-204939D01*
X1115372D01*
G01X1000110Y-164897D02*
Y-147397D01*
X1004476D01*
X1006223Y-148272D01*
X1007533Y-149439D01*
X1008625Y-151188D01*
X1009498Y-153231D01*
X1009716Y-156147D01*
X1009498Y-159064D01*
X1008625Y-161106D01*
X1007533Y-162856D01*
X1006223Y-164022D01*
X1004476Y-164897D01*
X1000110D01*
G01X1026343D02*
Y-153231D01*
G01Y-155272D02*
X1025470Y-154106D01*
X1024159Y-153522D01*
X1022631Y-153231D01*
X1021103Y-153814D01*
X1019793Y-154980D01*
X1018919Y-156730D01*
X1018483Y-159064D01*
X1018919Y-161397D01*
X1019793Y-163147D01*
X1021103Y-164314D01*
X1022631Y-164897D01*
X1024159Y-164605D01*
X1025470Y-163731D01*
X1026343Y-162564D01*
G01X1039913Y-147397D02*
Y-164897D01*
G01X1036856Y-153231D02*
X1042970D01*
G01X1054138Y-157022D02*
X1061125D01*
X1060470Y-154980D01*
X1059378Y-153814D01*
X1057850Y-153231D01*
X1056321Y-153522D01*
X1055011Y-154397D01*
X1054138Y-156439D01*
X1053701Y-158189D01*
Y-159939D01*
X1054138Y-161689D01*
X1055230Y-163439D01*
X1056540Y-164605D01*
X1058068Y-164897D01*
X1059596Y-164314D01*
X1061125Y-162564D01*
G54D12*
X9843Y153168D03*
Y265767D03*
Y353144D03*
Y717711D03*
Y762617D03*
Y875216D03*
Y1137420D03*
Y1250019D03*
Y1337396D03*
Y1701963D03*
Y1746869D03*
Y1859468D03*
G54D13*
X12560Y211435D03*
Y207498D03*
Y203561D03*
Y199624D03*
Y195687D03*
Y191750D03*
Y187813D03*
Y183876D03*
Y179939D03*
Y176002D03*
Y172065D03*
Y231121D03*
Y227184D03*
Y223247D03*
Y246869D03*
Y242932D03*
Y238995D03*
Y235058D03*
X12569Y395663D03*
Y391726D03*
Y387789D03*
Y383852D03*
Y379915D03*
Y375978D03*
Y372041D03*
Y478342D03*
Y474405D03*
Y470468D03*
Y466531D03*
Y462594D03*
Y458657D03*
Y454720D03*
Y450783D03*
Y446846D03*
Y442909D03*
Y438972D03*
Y435035D03*
Y431098D03*
Y427161D03*
Y423223D03*
Y411411D03*
Y407474D03*
Y403537D03*
Y399600D03*
Y561019D03*
Y557082D03*
Y553145D03*
Y549208D03*
Y545271D03*
Y541334D03*
Y537397D03*
Y533460D03*
Y529523D03*
Y525586D03*
Y521649D03*
Y517712D03*
Y513775D03*
Y509838D03*
Y505901D03*
Y501964D03*
Y498027D03*
Y494090D03*
Y490153D03*
Y486216D03*
Y482279D03*
Y643696D03*
Y639759D03*
Y635822D03*
Y631885D03*
Y627948D03*
Y624011D03*
Y620074D03*
Y616137D03*
Y612200D03*
Y604326D03*
Y608263D03*
Y600389D03*
Y596452D03*
Y592515D03*
Y584641D03*
Y588578D03*
Y580704D03*
Y576767D03*
Y572830D03*
Y568893D03*
Y564956D03*
Y698814D03*
Y694877D03*
Y690940D03*
Y687003D03*
Y683066D03*
Y679129D03*
Y675192D03*
Y671255D03*
Y667318D03*
Y663381D03*
Y659444D03*
Y655507D03*
Y651570D03*
Y647633D03*
X12560Y813010D03*
Y809073D03*
Y805136D03*
Y801199D03*
Y797262D03*
Y793325D03*
Y789388D03*
Y785451D03*
Y781514D03*
Y820884D03*
Y816947D03*
Y856318D03*
Y852381D03*
Y848444D03*
Y844507D03*
Y840570D03*
Y836633D03*
Y832696D03*
Y1195687D03*
Y1191750D03*
Y1187813D03*
Y1183876D03*
Y1179939D03*
Y1176002D03*
Y1172065D03*
Y1168128D03*
Y1164191D03*
Y1160254D03*
Y1156317D03*
Y1223247D03*
Y1219310D03*
Y1215373D03*
Y1211436D03*
Y1207499D03*
Y1231121D03*
Y1227184D03*
X12569Y1391726D03*
Y1387789D03*
Y1383852D03*
Y1379915D03*
Y1375978D03*
Y1372041D03*
Y1368104D03*
Y1364167D03*
Y1360230D03*
Y1356293D03*
Y1474405D03*
Y1470468D03*
Y1466531D03*
Y1462594D03*
Y1458657D03*
Y1454720D03*
Y1450783D03*
Y1446846D03*
Y1442909D03*
Y1438972D03*
Y1435035D03*
Y1431098D03*
Y1427161D03*
Y1423224D03*
Y1419287D03*
Y1415350D03*
Y1411413D03*
Y1407475D03*
Y1395663D03*
Y1557082D03*
Y1553145D03*
Y1549208D03*
Y1545271D03*
Y1541334D03*
Y1537397D03*
Y1533460D03*
Y1529523D03*
Y1525586D03*
Y1521649D03*
Y1517712D03*
Y1513775D03*
Y1509838D03*
Y1505901D03*
Y1501964D03*
Y1498027D03*
Y1494090D03*
Y1490153D03*
Y1486216D03*
Y1482279D03*
Y1478342D03*
Y1639759D03*
Y1635822D03*
Y1631885D03*
Y1627948D03*
Y1624011D03*
Y1620074D03*
Y1616137D03*
Y1612200D03*
Y1608263D03*
Y1604326D03*
Y1600389D03*
Y1596452D03*
Y1588578D03*
Y1592515D03*
Y1584641D03*
Y1580704D03*
Y1576767D03*
Y1568893D03*
Y1572830D03*
Y1564956D03*
Y1561019D03*
Y1683066D03*
Y1679129D03*
Y1675192D03*
Y1671255D03*
Y1667318D03*
Y1663381D03*
Y1659444D03*
Y1655507D03*
Y1651570D03*
Y1647633D03*
Y1643696D03*
X12560Y1805136D03*
Y1801199D03*
Y1797262D03*
Y1793325D03*
Y1789388D03*
Y1785451D03*
Y1781514D03*
Y1777577D03*
Y1773640D03*
Y1769703D03*
Y1765766D03*
Y1840570D03*
Y1836633D03*
Y1832696D03*
Y1828759D03*
Y1824822D03*
Y1820885D03*
Y1816948D03*
G54D14*
X17720Y1903144D03*
X29532Y309561D03*
Y1029522D03*
X129920Y17716D03*
X271657Y267711D03*
Y673223D03*
Y1078734D03*
Y1484246D03*
Y1889758D03*
X994098Y149601D03*
Y673223D03*
X994099Y1068892D03*
X994093Y1889751D03*
G54D15*
X8503Y1956700D03*
X46499Y69050D03*
X24000Y116500D03*
X57300Y452700D03*
X68800Y454300D03*
X33799Y553050D03*
X37849Y561450D03*
X66500Y543000D03*
X73000Y548700D03*
X31549Y566050D03*
X32505Y592986D03*
X32300Y597800D03*
X35766Y602721D03*
X35157Y608117D03*
X56500Y724500D03*
X43300Y806300D03*
X53999Y732050D03*
X53499Y739468D03*
X52299Y801450D03*
X59800Y812750D03*
X44899Y836250D03*
X96000Y866000D03*
X54799Y838050D03*
X88999Y882550D03*
X90000Y854500D03*
X89499Y892050D03*
X50399Y841450D03*
X54000Y819900D03*
X55299Y844350D03*
X61600Y850531D03*
X47200Y848431D03*
X43600Y883700D03*
X72300Y1018000D03*
X66000Y1020350D03*
X88005Y996217D03*
X93500Y1000300D03*
X70199Y1025050D03*
X79600Y1019100D03*
X14900Y1086100D03*
X74600Y1557500D03*
X85000Y1536450D03*
X41325Y1548747D03*
X91399Y1549550D03*
X81999Y1541550D03*
X72599Y1546650D03*
X70099Y1540550D03*
X60000Y1535500D03*
X78400Y1566400D03*
X73500Y1613000D03*
X56500Y1596500D03*
X49000Y1585500D03*
X78462Y1574918D03*
X60700Y1578962D03*
X37173Y1583074D03*
X40200Y1586800D03*
X93999Y1669550D03*
X89999Y1703050D03*
X68000Y1701000D03*
X62399Y1776050D03*
X91499Y1805549D03*
X62300Y1789650D03*
X68999Y1773550D03*
X40299Y1828750D03*
X50199Y1836052D03*
X49616Y1842667D03*
X94000Y1882500D03*
X89200Y1832000D03*
X45900Y1862900D03*
X37499Y1967749D03*
X32999Y1964549D03*
Y1956855D03*
X17455Y1928781D03*
X82400Y1931500D03*
X69100Y1918800D03*
X54800Y1929400D03*
X35521Y1930528D03*
X23999Y1932849D03*
X66900Y1891300D03*
X47999Y1891050D03*
X111300Y61900D03*
X178500Y63700D03*
X153700Y52700D03*
X147500Y109900D03*
X136500Y92400D03*
X156817Y165883D03*
X149400Y162500D03*
X144999Y425550D03*
X132349Y509050D03*
X157499Y502550D03*
X123999Y495050D03*
X134700Y553800D03*
X153000Y574000D03*
X137100Y570500D03*
X160900Y573000D03*
X99200Y994200D03*
X103900Y999400D03*
X109499Y1080550D03*
X111140Y1074659D03*
X120982Y1099733D03*
X109499Y1098350D03*
X104999Y1265050D03*
X113999Y1285550D03*
X105499Y1292550D03*
X136783Y1335517D03*
X143500Y1323500D03*
X131599Y1714150D03*
X116499Y1716750D03*
X135899Y1722550D03*
X118499Y1697750D03*
X127499Y1708250D03*
X121151Y1805128D03*
X103920Y1833104D03*
X115100Y1932000D03*
X231600Y63700D03*
X230200Y39100D03*
X220900Y38800D03*
X195499Y99050D03*
X204499Y116550D03*
X241099Y95050D03*
X194499Y109350D03*
X178999Y88550D03*
X184200Y484400D03*
X215500Y893610D03*
X204699Y896610D03*
X229800Y1077300D03*
X242000Y1069700D03*
X181000Y1361000D03*
X180400Y1374000D03*
X223029Y1465580D03*
X221199Y1556050D03*
X225499Y1606050D03*
X195499Y1852550D03*
X247252Y1826803D03*
X229800Y1872000D03*
X218100Y1882700D03*
X215999Y1955050D03*
X249499Y1924350D03*
X231999Y1918050D03*
X210999Y1945750D03*
X214999Y1914050D03*
X337799Y67110D03*
X304800Y29200D03*
X285999Y72550D03*
X312499D03*
X338499Y120550D03*
X315800Y104200D03*
X324800Y93100D03*
X342999Y169050D03*
X323499Y331550D03*
X284999Y342750D03*
X280345Y328896D03*
X331263Y742294D03*
X285264Y749050D03*
X284764Y738315D03*
X295999Y948550D03*
X286868Y1557582D03*
X290411Y1546462D03*
X299995Y1810554D03*
X264499Y1968050D03*
X331499Y1940750D03*
X385499Y59550D03*
X378428Y51119D03*
X347328Y31519D03*
X390411Y69638D03*
X392999Y337050D03*
X420499Y1335550D03*
X380999Y1618050D03*
X463499Y29550D03*
X460999Y819550D03*
X436499Y1836550D03*
X587499Y1844550D03*
X614999Y371550D03*
X636999Y914050D03*
X703999Y385550D03*
X755999Y1935050D03*
X756499Y1942550D03*
X759999Y39550D03*
X822200Y258000D03*
X816500Y270600D03*
X795199Y333050D03*
X789999Y340250D03*
X776199Y323050D03*
X772873Y330624D03*
X791999Y729350D03*
X770999Y726750D03*
X820900Y668000D03*
X812800Y679900D03*
X785826Y737954D03*
X799385Y757436D03*
X774199Y733050D03*
X795854Y1135926D03*
X768306Y1124321D03*
X774383Y1133235D03*
X788854Y1142626D03*
X782672Y1129146D03*
X825500Y1076300D03*
X815400Y1082500D03*
X806899Y1151850D03*
X811999Y1293550D03*
X774542Y1526350D03*
X804899Y1553250D03*
X774488Y1537495D03*
X787799Y1543550D03*
X797699Y1541050D03*
X833999Y1883050D03*
X775199Y1940050D03*
X799297Y1959333D03*
X835114Y1951150D03*
X790844Y1952360D03*
X849999Y44550D03*
X893999Y46550D03*
X848499Y67550D03*
X919542Y124007D03*
X849499Y91050D03*
X878499Y91550D03*
X847999Y119550D03*
X881999D03*
X918499Y107050D03*
X898999Y104550D03*
X904499Y121550D03*
X890999Y73050D03*
X872999Y294624D03*
X869399Y288124D03*
X864199Y321524D03*
X872599Y336224D03*
X870499Y724550D03*
X868750Y1128750D03*
X860499Y1192550D03*
X861849Y1383500D03*
X870294Y1375659D03*
X863838Y1542478D03*
X864799Y1532050D03*
X866516Y1498533D03*
X886506Y1721300D03*
X860085Y1715214D03*
X892517Y1714217D03*
X870783Y1742817D03*
X864414Y1944050D03*
X863699Y1902750D03*
X861000Y1917500D03*
X927999Y38050D03*
X951899Y45550D03*
X934999Y67050D03*
X945499Y116550D03*
X961568Y113567D03*
X951499Y81050D03*
G54D16*
X68898Y17047D03*
Y190275D03*
Y422559D03*
Y595787D03*
Y828071D03*
Y1001299D03*
Y1233583D03*
Y1406811D03*
Y1639095D03*
Y1812323D03*
X167323Y179803D03*
Y353031D03*
Y585315D03*
Y758543D03*
Y990827D03*
Y1164055D03*
Y1396339D03*
Y1569567D03*
Y1801851D03*
Y1975079D03*
X895669Y179803D03*
Y353031D03*
Y585315D03*
Y758543D03*
Y990827D03*
Y1164055D03*
Y1396339D03*
Y1569567D03*
Y1801851D03*
Y1975079D03*
G54D17*
X78150Y28858D03*
Y178464D03*
Y434370D03*
Y583976D03*
Y839882D03*
Y989488D03*
Y1245394D03*
Y1395000D03*
Y1650906D03*
Y1800512D03*
X158071Y191614D03*
Y341220D03*
Y597126D03*
Y746732D03*
Y1002638D03*
Y1152244D03*
Y1408150D03*
Y1557756D03*
Y1813662D03*
Y1963268D03*
X886417Y191614D03*
Y341220D03*
Y597126D03*
Y746732D03*
Y1002638D03*
Y1152244D03*
Y1408150D03*
Y1557756D03*
Y1813662D03*
Y1963268D03*
G54D18*
X1005807Y1636102D03*
Y1631102D03*
Y1626102D03*
Y1621102D03*
Y1676102D03*
Y1671102D03*
Y1666102D03*
Y1661102D03*
Y1656102D03*
Y1651102D03*
Y1646102D03*
Y1641102D03*
G54D19*
X1019291Y1416024D03*
Y1694212D03*
M02*
